FILE_TYPE = CONNECTIVITY;
{Allegro Design Entry HDL 17.4-2019 S026 (4007227) 1/17/2022}
"PAGE_NUMBER" = 150;
0"NC";
1"GND\g";
2"GND\g";
3"GND\g";
4"GND\g";
5"GND\g";
6"GND\g";
7"GND\g";
8"PVDD18_S5_P1\g";
9"JTAG_TCK";
10"JTAG_TMS";
11"JTAG_DBREQ_N";
12"JTAG_TRST_N";
13"PVDD18_S5_P0\g";
14"GND\g";
15"JTAG_P1_R_DBREQ_N";
16"JTAG_P1_R_TRST_N";
17"JTAG_P1_R_TMS";
18"JTAG_P1_R_TCK";
19"CPU1_JTAG_BUF_OE";
20"JTAG_P0_R_DBREQ_N";
21"JTAG_CPU0_DBREQ_N";
22"JTAG_CPU1_DBREQ_N";
23"JTAG_CPU1_TRST_N";
24"JTAG_CPU1_TMS";
25"JTAG_CPU1_TCK";
26"JTAG_P0_R_TCK";
27"JTAG_CPU0_TCK";
28"JTAG_P0_R_TRST_N";
29"JTAG_CPU0_TRST_N";
30"JTAG_P0_R_TMS";
31"JTAG_CPU0_TMS";
32"JTAG_TDO";
33"JTAG_TDO_R";
34"JTAG_CPUX_TDI_R1";
35"JTAG_CPUX_TDI";
36"U152_OE_N";
37"PVDD18_S5_P0\g";
38"GND\g";
39"PVDD18_S5_P0\g";
40"GND\g";
41"PVDD18_S5_P0\g";
42"PVDD18_S5_P0\g";
43"CPU0_JTAG_BUF_OE";
44"JTAG_TDI";
45"JTAG_CPUX_TDO";
%"GND"
"1","(-4650,5875)","0","pure_quanta_power","I13";
;
CDS_LIB"pure_quanta_power"
SIZE"1B"
HDL_POWER"GND";
"A<SIZE-1..0>\NAC"1;
%"Q_CAP"
"1","(-4650,6100)","0","pure_quanta","I14";
;
LOCATION"C1516"
$SEC"1"
CDS_SEC"1"
MATERIAL"X7R"
TOLERANCE"10%"
VALUE"0.1UF"
VOLTAGE"16V"
PACK_TYPE"C0402"
CDS_LIB"pure_quanta"
PART_NUMBER"CH4103K1B08";
"B"
$PN"2"1;
"A"
$PN"1"37;
%"UNIVERSAL_POWER"
"1","(-4800,6425)","0","pure_quanta_power","I15";
;
HDL_POWER"PVDD18_S5_P0"
CDS_LIB"pure_quanta_power";
"A"37;
%"GND"
"1","(-4800,4975)","0","pure_quanta_power","I16";
;
SIZE"1B"
CDS_LIB"pure_quanta_power"
HDL_POWER"GND";
"A<SIZE-1..0>\NAC"38;
%"GND"
"1","(-6050,5925)","0","pure_quanta_power","I17";
;
SIZE"1B"
CDS_LIB"pure_quanta_power"
HDL_POWER"GND";
"A<SIZE-1..0>\NAC"2;
%"UNIVERSAL_POWER"
"1","(-5850,6425)","0","pure_quanta_power","I18";
;
HDL_POWER"PVDD18_S5_P0"
CDS_LIB"pure_quanta_power";
"A"39;
%"Q_CAP"
"1","(-6050,6100)","0","pure_quanta","I19";
;
LOCATION"C1514"
$SEC"1"
CDS_SEC"1"
MATERIAL"X7R"
TOLERANCE"10%"
VALUE"0.1UF"
VOLTAGE"16V"
PACK_TYPE"C0402"
CDS_LIB"pure_quanta"
PART_NUMBER"CH4103K1B08";
"B"
$PN"2"2;
"A"
$PN"1"39;
%"Q_RES"
"1","(-3625,5550)","0","pure_quanta","I24";
;
LOCATION"R1641"
$SEC"1"
CDS_SEC"1"
VALUE"22"
TOLERANCE"1%"
MATERIAL"CHIP"
PACK_TYPE"0402LF"
WATTAGE"1/16W"
CDS_LIB"pure_quanta"
PART_NUMBER"CS02202FB02";
"B"
$PN"2"21;
"A"
$PN"1"20;
%"Q_RES"
"1","(-3625,5650)","0","pure_quanta","I25";
;
LOCATION"R1639"
$SEC"1"
CDS_SEC"1"
VALUE"22"
TOLERANCE"1%"
MATERIAL"CHIP"
PACK_TYPE"0402LF"
WATTAGE"1/16W"
CDS_LIB"pure_quanta"
PART_NUMBER"CS02202FB02";
"B"
$PN"2"31;
"A"
$PN"1"30;
%"Q_RES"
"1","(-3625,5600)","0","pure_quanta","I26";
;
LOCATION"R1640"
$SEC"1"
CDS_SEC"1"
VALUE"22"
TOLERANCE"1%"
MATERIAL"CHIP"
PACK_TYPE"0402LF"
WATTAGE"1/16W"
CDS_LIB"pure_quanta"
PART_NUMBER"CS02202FB02";
"B"
$PN"2"29;
"A"
$PN"1"28;
%"Q_RES"
"1","(-3625,5700)","0","pure_quanta","I27";
;
LOCATION"R1638"
$SEC"1"
CDS_SEC"1"
VALUE"22"
TOLERANCE"1%"
MATERIAL"CHIP"
PACK_TYPE"0402LF"
WATTAGE"1/16W"
CDS_LIB"pure_quanta"
PART_NUMBER"CS02202FB02";
"B"
$PN"2"27;
"A"
$PN"1"26;
%"SN74AVC4T774PWR"
"1","(-5325,3875)","0","pure_quanta","I28";
;
LOCATION"U151"
$SEC"1"
CDS_SEC"1"
VALUE"SN74AVC4T774PWR"
MATERIAL"IC"
PART_TYPE"SMLF"
NEEDS_NO_SIZE"TRUE"
CDS_LMAN_SYM_OUTLINE"-250,450,250,-450"
CDS_LIB"pure_quanta"
PART_NUMBER"AL04T774K00";
"VCCA"
$PN"16"13;
"VCCB"
$PN"15"8;
"B1"
$PN"14"18;
"B2"
$PN"13"17;
"B3"
$PN"12"16;
"B4"
$PN"11"15;
"GND"
$PN"10"14;
"OE \B"
$PN"9"19;
"DIR4"
$PN"8"13;
"DIR3"
$PN"7"13;
"A4"
$PN"6"11;
"A3"
$PN"5"12;
"A2"
$PN"4"10;
"A1"
$PN"3"9;
"DIR2"
$PN"2"13;
"DIR1"
$PN"1"13;
%"Q_RES"
"1","(-3625,4025)","0","pure_quanta","I33";
;
LOCATION"R1642"
$SEC"1"
CDS_SEC"1"
VALUE"22"
TOLERANCE"1%"
MATERIAL"CHIP"
PACK_TYPE"0402LF"
WATTAGE"1/16W"
CDS_LIB"pure_quanta"
PART_NUMBER"CS02202FB02";
"B"
$PN"2"25;
"A"
$PN"1"18;
%"Q_RES"
"1","(-3625,3975)","0","pure_quanta","I34";
;
LOCATION"R1643"
$SEC"1"
CDS_SEC"1"
VALUE"22"
TOLERANCE"1%"
MATERIAL"CHIP"
PACK_TYPE"0402LF"
WATTAGE"1/16W"
CDS_LIB"pure_quanta"
PART_NUMBER"CS02202FB02";
"B"
$PN"2"24;
"A"
$PN"1"17;
%"Q_RES"
"1","(-3625,3925)","0","pure_quanta","I35";
;
LOCATION"R1644"
$SEC"1"
CDS_SEC"1"
VALUE"22"
TOLERANCE"1%"
MATERIAL"CHIP"
PACK_TYPE"0402LF"
WATTAGE"1/16W"
CDS_LIB"pure_quanta"
PART_NUMBER"CS02202FB02";
"B"
$PN"2"23;
"A"
$PN"1"16;
%"Q_RES"
"1","(-3625,3875)","0","pure_quanta","I36";
;
LOCATION"R1645"
$SEC"1"
CDS_SEC"1"
VALUE"22"
TOLERANCE"1%"
MATERIAL"CHIP"
PACK_TYPE"0402LF"
WATTAGE"1/16W"
CDS_LIB"pure_quanta"
PART_NUMBER"CS02202FB02";
"B"
$PN"2"22;
"A"
$PN"1"15;
%"UNIVERSAL_POWER"
"1","(-4800,4725)","0","pure_quanta_power","I37";
;
HDL_POWER"PVDD18_S5_P1"
CDS_LIB"pure_quanta_power";
"A"8;
%"UNIVERSAL_POWER"
"1","(-5850,4725)","0","pure_quanta_power","I38";
;
HDL_POWER"PVDD18_S5_P0"
CDS_LIB"pure_quanta_power";
"A"13;
%"GND"
"1","(-4650,4175)","0","pure_quanta_power","I39";
;
CDS_LIB"pure_quanta_power"
SIZE"1B"
HDL_POWER"GND";
"A<SIZE-1..0>\NAC"3;
%"Q_CAP"
"1","(-4650,4400)","0","pure_quanta","I40";
;
LOCATION"C1517"
$SEC"1"
CDS_SEC"1"
MATERIAL"X7R"
TOLERANCE"10%"
VOLTAGE"16V"
VALUE"0.1UF"
PACK_TYPE"C0402"
CDS_LIB"pure_quanta"
PART_NUMBER"CH4103K1B08";
"B"
$PN"2"3;
"A"
$PN"1"8;
%"GND"
"1","(-4800,3350)","0","pure_quanta_power","I41";
;
SIZE"1B"
CDS_LIB"pure_quanta_power"
HDL_POWER"GND";
"A<SIZE-1..0>\NAC"14;
%"GND"
"1","(-6050,4225)","0","pure_quanta_power","I42";
;
CDS_LIB"pure_quanta_power"
SIZE"1B"
HDL_POWER"GND";
"A<SIZE-1..0>\NAC"4;
%"Q_CAP"
"1","(-6050,4450)","0","pure_quanta","I43";
;
LOCATION"C1515"
$SEC"1"
CDS_SEC"1"
TOLERANCE"10%"
VOLTAGE"16V"
MATERIAL"X7R"
VALUE"0.1UF"
PACK_TYPE"C0402"
CDS_LIB"pure_quanta"
PART_NUMBER"CH4103K1B08";
"B"
$PN"2"4;
"A"
$PN"1"13;
%"SN74AVC2T245RSWR"
"1","(-5325,2175)","2","pure_quanta","I60";
;
LOCATION"U152"
$SEC"1"
CDS_SEC"1"
MATERIAL"IC"
VALUE"SN74AVC2T245RSWR"
PART_TYPE"SMLF"
CDS_LIB"pure_quanta"
CDS_LMAN_SYM_OUTLINE"-250,375,250,-375"
NEEDS_NO_SIZE"TRUE"
PART_NUMBER"AL02T245000";
"DIR1"
$PN"10"42;
"A2"
$PN"9"33;
"A1"
$PN"8"44;
"VCCA"
$PN"7"41;
"VCCB"
$PN"6"41;
"B1"
$PN"5"34;
"B2"
$PN"4"45;
"GND"
$PN"3"40;
"OE_# \B"
$PN"2"36;
"DIR2"
$PN"1"40;
%"GND"
"1","(-6025,1750)","0","pure_quanta_power","I63";
;
SIZE"1B"
CDS_LIB"pure_quanta_power"
HDL_POWER"GND";
"A<SIZE-1..0>\NAC"40;
%"UNIVERSAL_POWER"
"1","(-4775,2975)","0","pure_quanta_power","I64";
;
HDL_POWER"PVDD18_S5_P0"
CDS_LIB"pure_quanta_power";
"A"41;
%"GND"
"1","(-4650,2475)","0","pure_quanta_power","I65";
;
CDS_LIB"pure_quanta_power"
SIZE"1B"
HDL_POWER"GND";
"A<SIZE-1..0>\NAC"5;
%"Q_CAP"
"1","(-4650,2700)","0","pure_quanta","I66";
;
LOCATION"C1518"
$SEC"1"
CDS_SEC"1"
MATERIAL"X7R"
TOLERANCE"10%"
VALUE"0.1UF"
VOLTAGE"16V"
PACK_TYPE"C0402"
CDS_LIB"pure_quanta"
PART_NUMBER"CH4103K1B08";
"B"
$PN"2"5;
"A"
$PN"1"41;
%"UNIVERSAL_POWER"
"1","(-6025,2975)","0","pure_quanta_power","I67";
;
HDL_POWER"PVDD18_S5_P0"
CDS_LIB"pure_quanta_power";
"A"42;
%"GND"
"1","(-6225,2475)","0","pure_quanta_power","I68";
;
CDS_LIB"pure_quanta_power"
SIZE"1B"
HDL_POWER"GND";
"A<SIZE-1..0>\NAC"6;
%"Q_CAP"
"1","(-6225,2700)","0","pure_quanta","I69";
;
LOCATION"C1513"
$SEC"1"
CDS_SEC"1"
TOLERANCE"10%"
VALUE"0.1UF"
VOLTAGE"16V"
MATERIAL"X7R"
PACK_TYPE"C0402"
CDS_LIB"pure_quanta"
PART_NUMBER"CH4103K1B08";
"B"
$PN"2"6;
"A"
$PN"1"42;
%"GND"
"1","(-6600,1525)","0","pure_quanta_power","I70";
;
SIZE"1B"
CDS_LIB"pure_quanta_power"
HDL_POWER"GND";
"A<SIZE-1..0>\NAC"7;
%"Q_RES"
"2","(-6600,1800)","2","pure_quanta","I71";
;
LOCATION"R1637"
$SEC"1"
CDS_SEC"1"
WATTAGE"1/16W"
MATERIAL"CHIP"
PACK_TYPE"0402LF"
TOLERANCE"5%"
VALUE"4.7K"
CDS_LIB"pure_quanta"
PART_NUMBER"CS24702JB10";
"A"
$PN"1"36;
"B"
$PN"2"7;
%"Q_RES"
"1","(-4200,2250)","0","pure_quanta","I76";
;
LOCATION"R6103"
$SEC"1"
CDS_SEC"1"
VALUE"0"
CDS_LIB"pure_quanta"
BOM_COST"MEM"
WATTAGE"1/16W"
MATERIAL"CHIP"
TOLERANCE"5%"
PACK_TYPE"0402LF"
PART_NUMBER"CS00002JB13";
"B"
$PN"2"35;
"A"
$PN"1"34;
%"Q_RES"
"1","(-6775,2150)","0","pure_quanta","I78";
;
LOCATION"R6109"
$SEC"1"
CDS_SEC"1"
VALUE"0"
MATERIAL"CHIP"
WATTAGE"1/16W"
TOLERANCE"5%"
PACK_TYPE"0402LF"
CDS_LIB"pure_quanta"
PART_NUMBER"CS00002JB13";
"B"
$PN"2"33;
"A"
$PN"1"32;
%"SN74AVC4T774PWR"
"1","(-5325,5550)","0","pure_quanta","I8";
;
LOCATION"U150"
$SEC"1"
CDS_SEC"1"
PART_TYPE"SMLF"
MATERIAL"IC"
VALUE"SN74AVC4T774PWR"
NEEDS_NO_SIZE"TRUE"
CDS_LMAN_SYM_OUTLINE"-250,450,250,-450"
CDS_LIB"pure_quanta"
PART_NUMBER"AL04T774K00";
"VCCA"
$PN"16"39;
"VCCB"
$PN"15"37;
"B1"
$PN"14"26;
"B2"
$PN"13"30;
"B3"
$PN"12"28;
"B4"
$PN"11"20;
"GND"
$PN"10"38;
"OE \B"
$PN"9"43;
"DIR4"
$PN"8"39;
"DIR3"
$PN"7"39;
"A4"
$PN"6"11;
"A3"
$PN"5"12;
"A2"
$PN"4"10;
"A1"
$PN"3"9;
"DIR2"
$PN"2"39;
"DIR1"
$PN"1"39;
END.
